FILE_TYPE = MACRO_DRAWING;
SET COLOR_WIRE YELLOW;
SET COLOR_PROP ORANGE;
SET COLOR_DOT WHITE;
SET COLOR_ARC YELLOW;
SET COLOR_BODY GREEN;
SET COLOR_NOTE PURPLE;
SET PROP_DISPLAY VALUE;
SET PAGE_NUMBER P389;
FORCEADD QUANTA_TITLE_BLOCK_C..1
(0 0);
FORCEPROP 1 LAST CUSTOM_TXT_CDS <NAME_2>
J 0
(-3175 50);
FORCEPROP 1 LAST CUSTOM_TXT_CDS <NAME_1>
J 0
(-3175 175);
FORCEPROP 1 LAST CUSTOM_TXT_CDS <Q_NUMBER>
J 0
(-1403 103);
DISPLAY 1.212766 (-1403 103);
FORCEPROP 1 LAST CUSTOM_TXT_CDS <Q_PROJ>
J 0
(-2382 102);
DISPLAY 1.212766 (-2382 102);
FORCEPROP 1 LAST CUSTOM_TXT_CDS <Q_REV>
J 0
(-184 103);
DISPLAY 1.212766 (-184 103);
FORCEPROP 1 LAST CUSTOM_TXT_CDS <CON_LAST_MODIFIED>
J 0
(-1885 15);
DISPLAY 0.978723 (-1885 15);
FORCEPROP 1 LAST CUSTOM_TXT_CDS <CON_PAGE_NUM> OF <CON_TOTAL_PAGES>
J 0
(-446 18);
DISPLAY 0.978723 (-446 18);
FORCEPROP 1 LAST Q_TITLE RETIMER_CPU0_P0(9)
J 0
(-9366 26);
DISPLAY 2.446809 (-9366 26);
PAINT GREEN (-9366 26);
FORCEPROP 2 LAST CDS_LIB pure_quanta
J 0
(0 0);
DISPLAY INVISIBLE (0 0);
FORCEPROP 1 LAST CDS_LMAN_SYM_OUTLINE -9475,6775,100,-125
J 0
(0 0);
DISPLAY 0.468085 (0 0);
PAINT GREEN (0 0);
DISPLAY INVISIBLE (0 0);
FORCEPROP 2 LAST PAGE_BORDER TRUE
J 0
(-7890 5250);
DISPLAY 0.638298 (-7890 5250);
PAINT PINK (-7890 5250);
DISPLAY INVISIBLE (-7890 5250);
FORCEPROP 2 LAST CDS_XR_PAGE_TITLE CR-281 : @T6G_MB_LIB.T6G(SCH_1):PAGE281
J 0
(-7890 5250);
DISPLAY 0.638298 (-7890 5250);
PAINT PINK (-7890 5250);
DISPLAY INVISIBLE (-7890 5250);
FORCEPROP 2 LAST CUSTOM_TXT_CDS <XR_PAGE_TITLE>
J 0
(-7890 5250);
DISPLAY 0.638298 (-7890 5250);
PAINT PINK (-7890 5250);
DISPLAY INVISIBLE (-7890 5250);
FORCEPROP 1 LAST COMMENT_BODY TRUE
J 0
(12 -13);
DISPLAY 0.978723 (12 -13);
PAINT GREEN (12 -13);
DISPLAY INVISIBLE (12 -13);
FORCEPROP 1 LAST Q_DEPT BU9
J 1
(-3763 49);
DISPLAY 1.957447 (-3763 49);
PAINT GREEN (-3763 49);
DISPLAY INVISIBLE (-3763 49);
FORCEPROP 0 LAST CDS_CON_LAST_MODIFIED Thu Aug 24 10:16:08 2023
J 0
(-1885 15);
DISPLAY INVISIBLE (-1885 15);
QUIT
